(kicad_pcb
	(version 20241229)
	(generator "pcbnew")
	(generator_version "9.0")
	(general
		(thickness 1.6642)
		(legacy_teardrops no)
	)
	(paper "A3")
	(title_block
		(title "PolarFire SoM")
		(date "2025-07-22")
		(rev "1.1.4")
		(company "Antmicro Ltd")
		(comment 1 "www.antmicro.com")
		(comment 9 "footprints 461-465 of 470")
	)
	(layers
		(0 "F.Cu" mixed)
		(4 "In1.Cu" power)
		(6 "In2.Cu" signal)
		(8 "In3.Cu" power)
		(10 "In4.Cu" signal)
		(12 "In5.Cu" power)
		(14 "In6.Cu" power)
		(16 "In7.Cu" signal)
		(18 "In8.Cu" power)
		(20 "In9.Cu" signal)
		(22 "In10.Cu" power)
		(24 "In11.Cu" signal)
		(26 "In12.Cu" signal)
		(2 "B.Cu" mixed)
		(9 "F.Adhes" user "F.Adhesive")
		(11 "B.Adhes" user "B.Adhesive")
		(13 "F.Paste" user)
		(15 "B.Paste" user)
		(5 "F.SilkS" user "F.Silkscreen")
		(7 "B.SilkS" user "B.Silkscreen")
		(1 "F.Mask" user)
		(3 "B.Mask" user)
		(17 "Dwgs.User" user "User.Drawings")
		(19 "Cmts.User" user "User.Comments")
		(21 "Eco1.User" user "User.Eco1")
		(23 "Eco2.User" user "User.Eco2")
		(25 "Edge.Cuts" user)
		(27 "Margin" user)
		(31 "F.CrtYd" user "F.Courtyard")
		(29 "B.CrtYd" user "B.Courtyard")
		(35 "F.Fab" user)
		(33 "B.Fab" user)
	)
	(footprint "antmicro-footprints:R_0603_1608Metric"
		(layer "B.Cu")
		(at 176.95 139.1375 90)
		(descr "Resistor SMD 0603")
		(tags "resistor SMD 0603")
		(property "Reference" "R21"
			(at 1.0625 2.525 0)
			(layer "B.SilkS")
			(effects
				(font
					(size 0.7 0.7)
					(thickness 0.15)
				)
				(justify left bottom mirror)
			)
		)
		(property "Value" "R_0R01_0603"
			(at 0 -1.6 270)
			(layer "B.Fab")
			(hide yes)
			(effects
				(font
					(size 0.7 0.7)
					(thickness 0.15)
				)
				(justify left bottom mirror)
			)
		)
		(property "Datasheet" "https://www.bourns.com/docs/product-datasheets/cfn-a.pdf"
			(at 0 0 90)
			(layer "F.Fab")
			(hide yes)
			(effects
				(font
					(size 1.27 1.27)
					(thickness 0.15)
				)
			)
		)
		(property "Description" "SMD Chip Resistor, 10 mohm, ± 1%, 0.5 W, 0603 [1608 Metric], Metal Foil, Current Sensing"
			(at 0 0 90)
			(layer "F.Fab")
			(hide yes)
			(effects
				(font
					(size 1.27 1.27)
					(thickness 0.15)
				)
			)
		)
		(property "Author" "Antmicro"
			(at 316.0875 -37.8125 0)
			(layer "B.Fab")
			(hide yes)
			(effects
				(font
					(size 1 1)
					(thickness 0.15)
				)
				(justify mirror)
			)
		)
		(property "License" "Apache-2.0"
			(at 316.0875 -37.8125 0)
			(layer "B.Fab")
			(hide yes)
			(effects
				(font
					(size 1 1)
					(thickness 0.15)
				)
				(justify mirror)
			)
		)
		(property "MPN" "CFN0603AFZ-R010ELF"
			(at 316.0875 -37.8125 0)
			(layer "B.Fab")
			(hide yes)
			(effects
				(font
					(size 1 1)
					(thickness 0.15)
				)
				(justify mirror)
			)
		)
		(property "Manufacturer" "Bourns"
			(at 316.0875 -37.8125 0)
			(layer "B.Fab")
			(hide yes)
			(effects
				(font
					(size 1 1)
					(thickness 0.15)
				)
				(justify mirror)
			)
		)
		(property "Public" ""
			(at 316.0875 -37.8125 0)
			(layer "B.Fab")
			(hide yes)
			(effects
				(font
					(size 1 1)
					(thickness 0.15)
				)
				(justify mirror)
			)
		)
		(property "Tolerance" "1%"
			(at 316.0875 -37.8125 0)
			(layer "B.Fab")
			(hide yes)
			(effects
				(font
					(size 1 1)
					(thickness 0.15)
				)
				(justify mirror)
			)
		)
		(property "Val" "0R01"
			(at 316.0875 -37.8125 0)
			(layer "B.Fab")
			(hide yes)
			(effects
				(font
					(size 1 1)
					(thickness 0.15)
				)
				(justify mirror)
			)
		)
		(sheetname "/Supply/")
		(sheetfile "supply.kicad_sch")
		(attr smd)
		(fp_line
			(start -0.15 -0.4)
			(end 0.15 -0.4)
			(stroke
				(width 0.15)
				(type solid)
			)
			(layer "B.SilkS")
		)
		(fp_line
			(start -0.15 0.4)
			(end 0.15 0.4)
			(stroke
				(width 0.15)
				(type solid)
			)
			(layer "B.SilkS")
		)
		(fp_rect
			(start -1.25 0.65)
			(end 1.25 -0.65)
			(stroke
				(width 0.05)
				(type solid)
			)
			(fill no)
			(layer "B.CrtYd")
		)
		(fp_rect
			(start -0.8 0.4)
			(end 0.8 -0.4)
			(stroke
				(width 0.15)
				(type solid)
			)
			(fill no)
			(layer "B.Fab")
		)
		(fp_text user "License: Apache-2.0"
			(at -1.25 -5.9 270)
			(layer "B.Fab")
			(effects
				(font
					(size 0.7 0.7)
					(thickness 0.15)
				)
				(justify left bottom mirror)
			)
		)
		(fp_text user "Author: Antmicro"
			(at -1.25 -4.9 270)
			(layer "B.Fab")
			(effects
				(font
					(size 0.7 0.7)
					(thickness 0.15)
				)
				(justify left bottom mirror)
			)
		)
		(fp_text user "${REFERENCE}"
			(at -1.25 -3.898 270)
			(layer "B.Fab")
			(effects
				(font
					(size 0.7 0.7)
					(thickness 0.15)
				)
				(justify left bottom mirror)
			)
		)
		(pad "1" smd roundrect
			(at -0.7 0 90)
			(size 0.8 1)
			(layers "B.Cu" "B.Mask" "B.Paste")
			(roundrect_rratio 0.2)
			(net 209 "/Supply/SENSE1_P")
			(pintype "passive")
		)
		(pad "2" smd roundrect
			(at 0.7 0 90)
			(size 0.8 1)
			(layers "B.Cu" "B.Mask" "B.Paste")
			(roundrect_rratio 0.2)
			(net 50 "+3V3")
			(pintype "passive")
		)
	)
	(footprint "antmicro-footprints:R_0402_1005Metric"
		(layer "B.Cu")
		(at 218.95 128.05 180)
		(descr "Resistor SMD 0402")
		(tags "resistor SMD 0402")
		(property "Reference" "R9"
			(at 0.96 0.38 90)
			(layer "B.SilkS")
			(effects
				(font
					(size 0.7 0.7)
					(thickness 0.15)
				)
				(justify left bottom mirror)
			)
		)
		(property "Value" "R_0R_0402"
			(at -1.011843 -1.772047 0)
			(layer "B.Fab")
			(hide yes)
			(effects
				(font
					(size 0.7 0.7)
					(thickness 0.15)
				)
				(justify left bottom mirror)
			)
		)
		(property "Datasheet" "https://industrial.panasonic.com/cdbs/www-data/pdf/RDA0000/AOA0000C301.pdf"
			(at 0 0 180)
			(layer "F.Fab")
			(hide yes)
			(effects
				(font
					(size 1.27 1.27)
					(thickness 0.15)
				)
			)
		)
		(property "Description" "SMD Chip Resistor, Jumper, 0 ohm, 100 mW, 0402 [1005 Metric], Thick Film, General Purpose"
			(at 0 0 180)
			(layer "F.Fab")
			(hide yes)
			(effects
				(font
					(size 1.27 1.27)
					(thickness 0.15)
				)
			)
		)
		(property "Author" "Antmicro"
			(at 437.9 256.1 0)
			(layer "B.Fab")
			(hide yes)
			(effects
				(font
					(size 1 1)
					(thickness 0.15)
				)
				(justify mirror)
			)
		)
		(property "Current" "1A"
			(at 437.9 256.1 0)
			(layer "B.Fab")
			(hide yes)
			(effects
				(font
					(size 1 1)
					(thickness 0.15)
				)
				(justify mirror)
			)
		)
		(property "License" "Apache-2.0"
			(at 437.9 256.1 0)
			(layer "B.Fab")
			(hide yes)
			(effects
				(font
					(size 1 1)
					(thickness 0.15)
				)
				(justify mirror)
			)
		)
		(property "MPN" "ERJ2GE0R00X"
			(at 437.9 256.1 0)
			(layer "B.Fab")
			(hide yes)
			(effects
				(font
					(size 1 1)
					(thickness 0.15)
				)
				(justify mirror)
			)
		)
		(property "Manufacturer" "Panasonic"
			(at 437.9 256.1 0)
			(layer "B.Fab")
			(hide yes)
			(effects
				(font
					(size 1 1)
					(thickness 0.15)
				)
				(justify mirror)
			)
		)
		(property "Public" ""
			(at 437.9 256.1 0)
			(layer "B.Fab")
			(hide yes)
			(effects
				(font
					(size 1 1)
					(thickness 0.15)
				)
				(justify mirror)
			)
		)
		(property "Tolerance" "~"
			(at 437.9 256.1 0)
			(layer "B.Fab")
			(hide yes)
			(effects
				(font
					(size 1 1)
					(thickness 0.15)
				)
				(justify mirror)
			)
		)
		(property "Val" "0R"
			(at 437.9 256.1 0)
			(layer "B.Fab")
			(hide yes)
			(effects
				(font
					(size 1 1)
					(thickness 0.15)
				)
				(justify mirror)
			)
		)
		(sheetname "/Supply/")
		(sheetfile "supply.kicad_sch")
		(attr smd)
		(fp_rect
			(start -0.925 0.47)
			(end 0.925 -0.47)
			(stroke
				(width 0.05)
				(type default)
			)
			(fill no)
			(layer "B.CrtYd")
		)
		(fp_rect
			(start -0.5 0.25)
			(end 0.5 -0.25)
			(stroke
				(width 0.15)
				(type solid)
			)
			(fill no)
			(layer "B.Fab")
		)
		(fp_text user "Author: Antmicro"
			(at -0.95 -4.169 0)
			(layer "B.Fab")
			(effects
				(font
					(size 0.7 0.7)
					(thickness 0.15)
				)
				(justify left bottom mirror)
			)
		)
		(fp_text user "${REFERENCE}"
			(at -0.95 -3.168 0)
			(layer "B.Fab")
			(effects
				(font
					(size 0.7 0.7)
					(thickness 0.15)
				)
				(justify left bottom mirror)
			)
		)
		(fp_text user "License: Apache-2.0"
			(at -0.95 -5.169 0)
			(layer "B.Fab")
			(effects
				(font
					(size 0.7 0.7)
					(thickness 0.15)
				)
				(justify left bottom mirror)
			)
		)
		(pad "1" smd roundrect
			(at -0.48 0 180)
			(size 0.59 0.64)
			(layers "B.Cu" "B.Mask" "B.Paste")
			(roundrect_rratio 0.25)
			(net 188 "Net-(R9-Pad1)")
			(pintype "passive")
		)
		(pad "2" smd roundrect
			(at 0.48 0 180)
			(size 0.59 0.64)
			(layers "B.Cu" "B.Mask" "B.Paste")
			(roundrect_rratio 0.25)
			(net 49 "VDDAUX")
			(pintype "passive")
		)
	)
	(footprint "antmicro-footprints:R_0402_1005Metric"
		(layer "B.Cu")
		(at 210.1925 133.347 180)
		(descr "Resistor SMD 0402")
		(tags "resistor SMD 0402")
		(property "Reference" "R30"
			(at -1.6075 -3.353 0)
			(layer "B.SilkS")
			(effects
				(font
					(size 0.7 0.7)
					(thickness 0.15)
				)
				(justify left bottom mirror)
			)
		)
		(property "Value" "R_10k_0402"
			(at -1.011843 -1.772047 0)
			(layer "B.Fab")
			(hide yes)
			(effects
				(font
					(size 0.7 0.7)
					(thickness 0.15)
				)
				(justify left bottom mirror)
			)
		)
		(property "Datasheet" "https://www.bourns.com/docs/product-datasheets/cr.pdf"
			(at 0 0 180)
			(layer "F.Fab")
			(hide yes)
			(effects
				(font
					(size 1.27 1.27)
					(thickness 0.15)
				)
			)
		)
		(property "Description" "SMD Chip Resistor, 10 kohm, ± 1%, 62.5 mW, 0402 [1005 Metric], Thick Film, General Purpose"
			(at 0 0 180)
			(layer "F.Fab")
			(hide yes)
			(effects
				(font
					(size 1.27 1.27)
					(thickness 0.15)
				)
			)
		)
		(property "Author" "Antmicro"
			(at 420.385 266.694 0)
			(layer "B.Fab")
			(hide yes)
			(effects
				(font
					(size 1 1)
					(thickness 0.15)
				)
				(justify mirror)
			)
		)
		(property "License" "Apache-2.0"
			(at 420.385 266.694 0)
			(layer "B.Fab")
			(hide yes)
			(effects
				(font
					(size 1 1)
					(thickness 0.15)
				)
				(justify mirror)
			)
		)
		(property "MPN" "CR0402-FX-1002GLF"
			(at 420.385 266.694 0)
			(layer "B.Fab")
			(hide yes)
			(effects
				(font
					(size 1 1)
					(thickness 0.15)
				)
				(justify mirror)
			)
		)
		(property "Manufacturer" "Bourns"
			(at 420.385 266.694 0)
			(layer "B.Fab")
			(hide yes)
			(effects
				(font
					(size 1 1)
					(thickness 0.15)
				)
				(justify mirror)
			)
		)
		(property "Public" ""
			(at 420.385 266.694 0)
			(layer "B.Fab")
			(hide yes)
			(effects
				(font
					(size 1 1)
					(thickness 0.15)
				)
				(justify mirror)
			)
		)
		(property "Tolerance" "1%"
			(at 420.385 266.694 0)
			(layer "B.Fab")
			(hide yes)
			(effects
				(font
					(size 1 1)
					(thickness 0.15)
				)
				(justify mirror)
			)
		)
		(property "Val" "10k"
			(at 420.385 266.694 0)
			(layer "B.Fab")
			(hide yes)
			(effects
				(font
					(size 1 1)
					(thickness 0.15)
				)
				(justify mirror)
			)
		)
		(sheetname "/Memory/")
		(sheetfile "memory.kicad_sch")
		(attr smd)
		(fp_rect
			(start -0.925 0.47)
			(end 0.925 -0.47)
			(stroke
				(width 0.05)
				(type default)
			)
			(fill no)
			(layer "B.CrtYd")
		)
		(fp_rect
			(start -0.5 0.25)
			(end 0.5 -0.25)
			(stroke
				(width 0.15)
				(type solid)
			)
			(fill no)
			(layer "B.Fab")
		)
		(fp_text user "License: Apache-2.0"
			(at -0.95 -5.169 0)
			(layer "B.Fab")
			(effects
				(font
					(size 0.7 0.7)
					(thickness 0.15)
				)
				(justify left bottom mirror)
			)
		)
		(fp_text user "${REFERENCE}"
			(at -0.95 -3.168 0)
			(layer "B.Fab")
			(effects
				(font
					(size 0.7 0.7)
					(thickness 0.15)
				)
				(justify left bottom mirror)
			)
		)
		(fp_text user "Author: Antmicro"
			(at -0.95 -4.169 0)
			(layer "B.Fab")
			(effects
				(font
					(size 0.7 0.7)
					(thickness 0.15)
				)
				(justify left bottom mirror)
			)
		)
		(pad "1" smd roundrect
			(at -0.48 0 180)
			(size 0.59 0.64)
			(layers "B.Cu" "B.Mask" "B.Paste")
			(roundrect_rratio 0.25)
			(net 417 "GND")
			(pintype "passive")
		)
		(pad "2" smd roundrect
			(at 0.48 0 180)
			(size 0.59 0.64)
			(layers "B.Cu" "B.Mask" "B.Paste")
			(roundrect_rratio 0.25)
			(net 390 "/FPGA MSSIO/EMMC.STRB")
			(pintype "passive")
		)
	)
	(footprint "antmicro-footprints:R_0402_1005Metric"
		(layer "B.Cu")
		(at 225.6 143.345 180)
		(descr "Resistor SMD 0402")
		(tags "resistor SMD 0402")
		(property "Reference" "R149"
			(at -3.8 -0.405 0)
			(layer "B.SilkS")
			(effects
				(font
					(size 0.7 0.7)
					(thickness 0.15)
				)
				(justify left bottom mirror)
			)
		)
		(property "Value" "R_10k_0402"
			(at -1.011843 -1.772047 0)
			(layer "B.Fab")
			(hide yes)
			(effects
				(font
					(size 0.7 0.7)
					(thickness 0.15)
				)
				(justify left bottom mirror)
			)
		)
		(property "Datasheet" "https://www.bourns.com/docs/product-datasheets/cr.pdf"
			(at 0 0 180)
			(layer "F.Fab")
			(hide yes)
			(effects
				(font
					(size 1.27 1.27)
					(thickness 0.15)
				)
			)
		)
		(property "Description" "SMD Chip Resistor, 10 kohm, ± 1%, 62.5 mW, 0402 [1005 Metric], Thick Film, General Purpose"
			(at 0 0 180)
			(layer "F.Fab")
			(hide yes)
			(effects
				(font
					(size 1.27 1.27)
					(thickness 0.15)
				)
			)
		)
		(property "Author" "Antmicro"
			(at 451.2 286.69 0)
			(layer "B.Fab")
			(hide yes)
			(effects
				(font
					(size 1 1)
					(thickness 0.15)
				)
				(justify mirror)
			)
		)
		(property "License" "Apache-2.0"
			(at 451.2 286.69 0)
			(layer "B.Fab")
			(hide yes)
			(effects
				(font
					(size 1 1)
					(thickness 0.15)
				)
				(justify mirror)
			)
		)
		(property "MPN" "CR0402-FX-1002GLF"
			(at 451.2 286.69 0)
			(layer "B.Fab")
			(hide yes)
			(effects
				(font
					(size 1 1)
					(thickness 0.15)
				)
				(justify mirror)
			)
		)
		(property "Manufacturer" "Bourns"
			(at 451.2 286.69 0)
			(layer "B.Fab")
			(hide yes)
			(effects
				(font
					(size 1 1)
					(thickness 0.15)
				)
				(justify mirror)
			)
		)
		(property "Public" ""
			(at 451.2 286.69 0)
			(layer "B.Fab")
			(hide yes)
			(effects
				(font
					(size 1 1)
					(thickness 0.15)
				)
				(justify mirror)
			)
		)
		(property "Tolerance" "1%"
			(at 451.2 286.69 0)
			(layer "B.Fab")
			(hide yes)
			(effects
				(font
					(size 1 1)
					(thickness 0.15)
				)
				(justify mirror)
			)
		)
		(property "Val" "10k"
			(at 451.2 286.69 0)
			(layer "B.Fab")
			(hide yes)
			(effects
				(font
					(size 1 1)
					(thickness 0.15)
				)
				(justify mirror)
			)
		)
		(sheetname "/WiFi_Bluetooth/")
		(sheetfile "wifi_bt.kicad_sch")
		(attr smd)
		(fp_rect
			(start -0.925 0.47)
			(end 0.925 -0.47)
			(stroke
				(width 0.05)
				(type default)
			)
			(fill no)
			(layer "B.CrtYd")
		)
		(fp_rect
			(start -0.5 0.25)
			(end 0.5 -0.25)
			(stroke
				(width 0.15)
				(type solid)
			)
			(fill no)
			(layer "B.Fab")
		)
		(fp_text user "License: Apache-2.0"
			(at -0.95 -5.169 0)
			(layer "B.Fab")
			(effects
				(font
					(size 0.7 0.7)
					(thickness 0.15)
				)
				(justify left bottom mirror)
			)
		)
		(fp_text user "${REFERENCE}"
			(at -0.95 -3.168 0)
			(layer "B.Fab")
			(effects
				(font
					(size 0.7 0.7)
					(thickness 0.15)
				)
				(justify left bottom mirror)
			)
		)
		(fp_text user "Author: Antmicro"
			(at -0.95 -4.169 0)
			(layer "B.Fab")
			(effects
				(font
					(size 0.7 0.7)
					(thickness 0.15)
				)
				(justify left bottom mirror)
			)
		)
		(pad "1" smd roundrect
			(at -0.48 0 180)
			(size 0.59 0.64)
			(layers "B.Cu" "B.Mask" "B.Paste")
			(roundrect_rratio 0.25)
			(net 417 "GND")
			(pintype "passive")
		)
		(pad "2" smd roundrect
			(at 0.48 0 180)
			(size 0.59 0.64)
			(layers "B.Cu" "B.Mask" "B.Paste")
			(roundrect_rratio 0.25)
			(net 423 "/WiFi_Bluetooth/STRAP_2")
			(pintype "passive")
		)
	)
	(footprint "antmicro-footprints:C_0402_1005Metric"
		(layer "B.Cu")
		(at 195.87 146.76 -90)
		(descr "Capacitor SMD 0402")
		(tags "capacitor SMD 0402")
		(property "Reference" "C182"
			(at 0.79 0.02 90)
			(layer "B.SilkS")
			(effects
				(font
					(size 0.7 0.7)
					(thickness 0.15)
				)
				(justify left bottom mirror)
			)
		)
		(property "Value" "C_100n_0402"
			(at -1.022927 -2.155213 90)
			(layer "B.Fab")
			(hide yes)
			(effects
				(font
					(size 0.7 0.7)
					(thickness 0.15)
				)
				(justify left bottom mirror)
			)
		)
		(property "Datasheet" "https://www.murata.com/products/productdetail?partno=GRM155R61H104KE14%23"
			(at 0 0 270)
			(layer "F.Fab")
			(hide yes)
			(effects
				(font
					(size 1.27 1.27)
					(thickness 0.15)
				)
			)
		)
		(property "Description" "SMD Multilayer Ceramic Capacitor, 0.1 µF, 50 V, 0402 [1005 Metric], ± 10%, X5R, GRM Series"
			(at 0 0 270)
			(layer "F.Fab")
			(hide yes)
			(effects
				(font
					(size 1.27 1.27)
					(thickness 0.15)
				)
			)
		)
		(property "Author" "Antmicro"
			(at 49.11 342.63 0)
			(layer "B.Fab")
			(hide yes)
			(effects
				(font
					(size 1 1)
					(thickness 0.15)
				)
				(justify mirror)
			)
		)
		(property "Dielectric" "X5R"
			(at 49.11 342.63 0)
			(layer "B.Fab")
			(hide yes)
			(effects
				(font
					(size 1 1)
					(thickness 0.15)
				)
				(justify mirror)
			)
		)
		(property "License" "Apache-2.0"
			(at 49.11 342.63 0)
			(layer "B.Fab")
			(hide yes)
			(effects
				(font
					(size 1 1)
					(thickness 0.15)
				)
				(justify mirror)
			)
		)
		(property "MPN" "GRM155R61H104KE14D"
			(at 49.11 342.63 0)
			(layer "B.Fab")
			(hide yes)
			(effects
				(font
					(size 1 1)
					(thickness 0.15)
				)
				(justify mirror)
			)
		)
		(property "Manufacturer" "Murata"
			(at 49.11 342.63 0)
			(layer "B.Fab")
			(hide yes)
			(effects
				(font
					(size 1 1)
					(thickness 0.15)
				)
				(justify mirror)
			)
		)
		(property "Public" ""
			(at 49.11 342.63 0)
			(layer "B.Fab")
			(hide yes)
			(effects
				(font
					(size 1 1)
					(thickness 0.15)
				)
				(justify mirror)
			)
		)
		(property "Val" "100n"
			(at 49.11 342.63 0)
			(layer "B.Fab")
			(hide yes)
			(effects
				(font
					(size 1 1)
					(thickness 0.15)
				)
				(justify mirror)
			)
		)
		(property "Voltage" "50V"
			(at 49.11 342.63 0)
			(layer "B.Fab")
			(hide yes)
			(effects
				(font
					(size 1 1)
					(thickness 0.15)
				)
				(justify mirror)
			)
		)
		(sheetname "/HDMI/")
		(sheetfile "hdmi.kicad_sch")
		(attr smd)
		(fp_rect
			(start -0.925 0.47)
			(end 0.925 -0.47)
			(stroke
				(width 0.05)
				(type default)
			)
			(fill no)
			(layer "B.CrtYd")
		)
		(fp_line
			(start -0.494 0.25)
			(end 0.504 0.25)
			(stroke
				(width 0.15)
				(type solid)
			)
			(layer "B.Fab")
		)
		(fp_line
			(start 0.504 0.25)
			(end 0.504 -0.248)
			(stroke
				(width 0.15)
				(type solid)
			)
			(layer "B.Fab")
		)
		(fp_line
			(start -0.494 -0.248)
			(end -0.494 0.25)
			(stroke
				(width 0.15)
				(type solid)
			)
			(layer "B.Fab")
		)
		(fp_line
			(start 0.504 -0.248)
			(end -0.494 -0.248)
			(stroke
				(width 0.15)
				(type solid)
			)
			(layer "B.Fab")
		)
		(fp_text user "${REFERENCE}"
			(at -0.939 -4.599 90)
			(layer "B.Fab")
			(effects
				(font
					(size 0.7 0.7)
					(thickness 0.15)
				)
				(justify left bottom mirror)
			)
		)
		(fp_text user "License: Apache-2.0"
			(at -0.939 -5.799 90)
			(layer "B.Fab")
			(effects
				(font
					(size 0.7 0.7)
					(thickness 0.15)
				)
				(justify left bottom mirror)
			)
		)
		(fp_text user "Author: Antmicro"
			(at -0.939 -3.399 90)
			(layer "B.Fab")
			(effects
				(font
					(size 0.7 0.7)
					(thickness 0.15)
				)
				(justify left bottom mirror)
			)
		)
		(pad "1" smd roundrect
			(at -0.48 0 270)
			(size 0.59 0.64)
			(layers "B.Cu" "B.Mask" "B.Paste")
			(roundrect_rratio 0.25)
			(net 553 "/HDMI/HDMI_3V3")
			(pintype "passive")
		)
		(pad "2" smd roundrect
			(at 0.48 0 270)
			(size 0.59 0.64)
			(layers "B.Cu" "B.Mask" "B.Paste")
			(roundrect_rratio 0.25)
			(net 417 "GND")
			(pintype "passive")
		)
	)
)
